(kicad_sch (version 20230121) (generator eeschema)

  (paper "A3")

  (title_block
    (title "Scalenode CM4 Baseboard")
    (date "2024-03-26")
    (rev "1.1.3")
    (company "Antmicro")
    (comment 1 "www.antmicro.com")
  )

  (junction (at 99.06 52.07) (diameter 0) (color 0 0 0 0)
  )
  (junction (at 99.06 76.2) (diameter 0) (color 0 0 0 0)
  )
  (junction (at 91.44 63.5) (diameter 0) (color 0 0 0 0)
  )
  (junction (at 91.44 87.63) (diameter 0) (color 0 0 0 0)
  )
  (junction (at 83.82 100.33) (diameter 0) (color 0 0 0 0)
  )
  (junction (at 133.35 68.58) (diameter 0) (color 0 0 0 0)
  )
  (junction (at 83.82 52.07) (diameter 0) (color 0 0 0 0)
  )
  (junction (at 83.82 76.2) (diameter 0) (color 0 0 0 0)
  )
  (junction (at 99.06 100.33) (diameter 0) (color 0 0 0 0)
  )
  (junction (at 91.44 100.33) (diameter 0) (color 0 0 0 0)
  )
  (junction (at 76.2 39.37) (diameter 0) (color 0 0 0 0)
  )
  (junction (at 83.82 39.37) (diameter 0) (color 0 0 0 0)
  )
  (junction (at 125.73 54.61) (diameter 0) (color 0 0 0 0)
  )
  (junction (at 91.44 39.37) (diameter 0) (color 0 0 0 0)
  )
  (junction (at 144.78 106.68) (diameter 0) (color 0 0 0 0)
  )
  (junction (at 140.97 71.12) (diameter 0) (color 0 0 0 0)
  )
  (junction (at 125.73 66.04) (diameter 0) (color 0 0 0 0)
  )
  (junction (at 133.35 54.61) (diameter 0) (color 0 0 0 0)
  )
  (junction (at 76.2 63.5) (diameter 0) (color 0 0 0 0)
  )
  (junction (at 83.82 87.63) (diameter 0) (color 0 0 0 0)
  )
  (junction (at 76.2 87.63) (diameter 0) (color 0 0 0 0)
  )
  (junction (at 91.44 76.2) (diameter 0) (color 0 0 0 0)
  )
  (junction (at 83.82 63.5) (diameter 0) (color 0 0 0 0)
  )
  (junction (at 91.44 52.07) (diameter 0) (color 0 0 0 0)
  )

  (no_connect (at 184.15 91.44))
  (no_connect (at 146.05 78.74))
  (no_connect (at 146.05 76.2))
  (no_connect (at 146.05 73.66))
  (no_connect (at 184.15 73.66))
  (no_connect (at 184.15 66.04))
  (no_connect (at 184.15 99.06))
  (no_connect (at 184.15 104.14))
  (no_connect (at 184.15 106.68))
  (no_connect (at 184.15 96.52))
  (no_connect (at 184.15 81.28))
  (no_connect (at 190.5 139.7))
  (no_connect (at 146.05 63.5))
  (no_connect (at 190.5 127))
  (no_connect (at 184.15 83.82))
  (no_connect (at 184.15 88.9))
  (no_connect (at 184.15 68.58))
  (no_connect (at 184.15 76.2))

  (wire (pts (xy 184.15 44.45) (xy 205.74 44.45))
    (stroke (width 0) (type default))
  )
  (wire (pts (xy 99.06 46.99) (xy 99.06 52.07))
    (stroke (width 0) (type default))
  )
  (wire (pts (xy 146.05 66.04) (xy 125.73 66.04))
    (stroke (width 0) (type default))
  )
  (wire (pts (xy 83.82 63.5) (xy 83.82 66.04))
    (stroke (width 0) (type default))
  )
  (wire (pts (xy 76.2 87.63) (xy 76.2 90.17))
    (stroke (width 0) (type default))
  )
  (wire (pts (xy 76.2 46.99) (xy 76.2 52.07))
    (stroke (width 0) (type default))
  )
  (wire (pts (xy 76.2 39.37) (xy 71.12 39.37))
    (stroke (width 0) (type default))
  )
  (wire (pts (xy 138.43 81.28) (xy 146.05 81.28))
    (stroke (width 0) (type default))
  )
  (wire (pts (xy 76.2 52.07) (xy 83.82 52.07))
    (stroke (width 0) (type default))
  )
  (wire (pts (xy 76.2 39.37) (xy 76.2 41.91))
    (stroke (width 0) (type default))
  )
  (wire (pts (xy 76.2 63.5) (xy 76.2 66.04))
    (stroke (width 0) (type default))
  )
  (wire (pts (xy 99.06 53.34) (xy 99.06 52.07))
    (stroke (width 0) (type default))
  )
  (polyline (pts (xy 72.39 38.1) (xy 72.39 53.34))
    (stroke (width 0) (type default))
  )
  (polyline (pts (xy 101.6 77.47) (xy 72.39 77.47))
    (stroke (width 0) (type default))
  )
  (wire (pts (xy 76.2 76.2) (xy 83.82 76.2))
    (stroke (width 0) (type default))
  )
  (wire (pts (xy 91.44 87.63) (xy 91.44 90.17))
    (stroke (width 0) (type default))
  )
  (wire (pts (xy 83.82 76.2) (xy 91.44 76.2))
    (stroke (width 0) (type default))
  )
  (polyline (pts (xy 72.39 38.1) (xy 101.6 38.1))
    (stroke (width 0) (type default))
  )
  (wire (pts (xy 83.82 46.99) (xy 83.82 52.07))
    (stroke (width 0) (type default))
  )
  (polyline (pts (xy 101.6 101.6) (xy 72.39 101.6))
    (stroke (width 0) (type default))
  )
  (wire (pts (xy 99.06 76.2) (xy 91.44 76.2))
    (stroke (width 0) (type default))
  )
  (wire (pts (xy 184.15 58.42) (xy 205.74 58.42))
    (stroke (width 0) (type default))
  )
  (wire (pts (xy 99.06 39.37) (xy 99.06 41.91))
    (stroke (width 0) (type default))
  )
  (wire (pts (xy 144.78 107.95) (xy 144.78 106.68))
    (stroke (width 0) (type default))
  )
  (wire (pts (xy 133.35 54.61) (xy 125.73 54.61))
    (stroke (width 0) (type default))
  )
  (wire (pts (xy 83.82 87.63) (xy 76.2 87.63))
    (stroke (width 0) (type default))
  )
  (polyline (pts (xy 101.6 86.36) (xy 101.6 101.6))
    (stroke (width 0) (type default))
  )
  (wire (pts (xy 146.05 68.58) (xy 133.35 68.58))
    (stroke (width 0) (type default))
  )
  (wire (pts (xy 127 81.28) (xy 130.81 81.28))
    (stroke (width 0) (type default))
  )
  (wire (pts (xy 125.73 60.96) (xy 125.73 66.04))
    (stroke (width 0) (type default))
  )
  (wire (pts (xy 91.44 63.5) (xy 91.44 66.04))
    (stroke (width 0) (type default))
  )
  (wire (pts (xy 91.44 52.07) (xy 99.06 52.07))
    (stroke (width 0) (type default))
  )
  (wire (pts (xy 91.44 46.99) (xy 91.44 52.07))
    (stroke (width 0) (type default))
  )
  (wire (pts (xy 125.73 66.04) (xy 124.46 66.04))
    (stroke (width 0) (type default))
  )
  (wire (pts (xy 140.97 71.12) (xy 124.46 71.12))
    (stroke (width 0) (type default))
  )
  (wire (pts (xy 99.06 71.12) (xy 99.06 76.2))
    (stroke (width 0) (type default))
  )
  (wire (pts (xy 99.06 95.25) (xy 99.06 100.33))
    (stroke (width 0) (type default))
  )
  (polyline (pts (xy 72.39 62.23) (xy 72.39 77.47))
    (stroke (width 0) (type default))
  )
  (polyline (pts (xy 101.6 38.1) (xy 101.6 53.34))
    (stroke (width 0) (type default))
  )
  (wire (pts (xy 91.44 39.37) (xy 83.82 39.37))
    (stroke (width 0) (type default))
  )
  (wire (pts (xy 99.06 63.5) (xy 91.44 63.5))
    (stroke (width 0) (type default))
  )
  (polyline (pts (xy 72.39 86.36) (xy 72.39 101.6))
    (stroke (width 0) (type default))
  )
  (wire (pts (xy 125.73 54.61) (xy 124.46 54.61))
    (stroke (width 0) (type default))
  )
  (wire (pts (xy 184.15 60.96) (xy 205.74 60.96))
    (stroke (width 0) (type default))
  )
  (wire (pts (xy 99.06 63.5) (xy 99.06 66.04))
    (stroke (width 0) (type default))
  )
  (wire (pts (xy 83.82 100.33) (xy 91.44 100.33))
    (stroke (width 0) (type default))
  )
  (wire (pts (xy 76.2 63.5) (xy 71.12 63.5))
    (stroke (width 0) (type default))
  )
  (wire (pts (xy 99.06 101.6) (xy 99.06 100.33))
    (stroke (width 0) (type default))
  )
  (wire (pts (xy 133.35 54.61) (xy 133.35 55.88))
    (stroke (width 0) (type default))
  )
  (wire (pts (xy 83.82 39.37) (xy 76.2 39.37))
    (stroke (width 0) (type default))
  )
  (wire (pts (xy 99.06 87.63) (xy 91.44 87.63))
    (stroke (width 0) (type default))
  )
  (wire (pts (xy 124.46 68.58) (xy 133.35 68.58))
    (stroke (width 0) (type default))
  )
  (wire (pts (xy 76.2 95.25) (xy 76.2 100.33))
    (stroke (width 0) (type default))
  )
  (wire (pts (xy 76.2 87.63) (xy 71.12 87.63))
    (stroke (width 0) (type default))
  )
  (wire (pts (xy 83.82 52.07) (xy 91.44 52.07))
    (stroke (width 0) (type default))
  )
  (wire (pts (xy 76.2 71.12) (xy 76.2 76.2))
    (stroke (width 0) (type default))
  )
  (wire (pts (xy 125.73 54.61) (xy 125.73 55.88))
    (stroke (width 0) (type default))
  )
  (wire (pts (xy 83.82 95.25) (xy 83.82 100.33))
    (stroke (width 0) (type default))
  )
  (polyline (pts (xy 72.39 62.23) (xy 101.6 62.23))
    (stroke (width 0) (type default))
  )
  (wire (pts (xy 91.44 63.5) (xy 83.82 63.5))
    (stroke (width 0) (type default))
  )
  (wire (pts (xy 83.82 87.63) (xy 83.82 90.17))
    (stroke (width 0) (type default))
  )
  (wire (pts (xy 83.82 63.5) (xy 76.2 63.5))
    (stroke (width 0) (type default))
  )
  (wire (pts (xy 91.44 71.12) (xy 91.44 76.2))
    (stroke (width 0) (type default))
  )
  (wire (pts (xy 140.97 54.61) (xy 140.97 55.88))
    (stroke (width 0) (type default))
  )
  (polyline (pts (xy 101.6 62.23) (xy 101.6 77.47))
    (stroke (width 0) (type default))
  )
  (wire (pts (xy 133.35 60.96) (xy 133.35 68.58))
    (stroke (width 0) (type default))
  )
  (wire (pts (xy 99.06 100.33) (xy 91.44 100.33))
    (stroke (width 0) (type default))
  )
  (wire (pts (xy 99.06 87.63) (xy 99.06 90.17))
    (stroke (width 0) (type default))
  )
  (wire (pts (xy 146.05 71.12) (xy 140.97 71.12))
    (stroke (width 0) (type default))
  )
  (wire (pts (xy 91.44 95.25) (xy 91.44 100.33))
    (stroke (width 0) (type default))
  )
  (wire (pts (xy 119.38 81.28) (xy 121.92 81.28))
    (stroke (width 0) (type default))
  )
  (wire (pts (xy 83.82 71.12) (xy 83.82 76.2))
    (stroke (width 0) (type default))
  )
  (wire (pts (xy 99.06 77.47) (xy 99.06 76.2))
    (stroke (width 0) (type default))
  )
  (polyline (pts (xy 101.6 53.34) (xy 72.39 53.34))
    (stroke (width 0) (type default))
  )
  (wire (pts (xy 146.05 104.14) (xy 144.78 104.14))
    (stroke (width 0) (type default))
  )
  (wire (pts (xy 184.15 41.91) (xy 205.74 41.91))
    (stroke (width 0) (type default))
  )
  (wire (pts (xy 184.15 53.34) (xy 205.74 53.34))
    (stroke (width 0) (type default))
  )
  (wire (pts (xy 184.15 50.8) (xy 205.74 50.8))
    (stroke (width 0) (type default))
  )
  (wire (pts (xy 76.2 100.33) (xy 83.82 100.33))
    (stroke (width 0) (type default))
  )
  (wire (pts (xy 144.78 104.14) (xy 144.78 106.68))
    (stroke (width 0) (type default))
  )
  (wire (pts (xy 99.06 39.37) (xy 91.44 39.37))
    (stroke (width 0) (type default))
  )
  (wire (pts (xy 140.97 60.96) (xy 140.97 71.12))
    (stroke (width 0) (type default))
  )
  (wire (pts (xy 91.44 39.37) (xy 91.44 41.91))
    (stroke (width 0) (type default))
  )
  (wire (pts (xy 144.78 106.68) (xy 146.05 106.68))
    (stroke (width 0) (type default))
  )
  (wire (pts (xy 144.78 41.91) (xy 146.05 41.91))
    (stroke (width 0) (type default))
  )
  (wire (pts (xy 140.97 54.61) (xy 133.35 54.61))
    (stroke (width 0) (type default))
  )
  (wire (pts (xy 91.44 87.63) (xy 83.82 87.63))
    (stroke (width 0) (type default))
  )
  (polyline (pts (xy 72.39 86.36) (xy 101.6 86.36))
    (stroke (width 0) (type default))
  )
  (wire (pts (xy 83.82 39.37) (xy 83.82 41.91))
    (stroke (width 0) (type default))
  )

  (text "2242 Form Factor" (at 193.04 123.19 0)
    (effects (font (size 1.27 1.27)) (justify left bottom))
  )
  (text "RPi4 CM DS states that AC coupling capacitors for Tx \nare already onboard and if connecting to external card\nRx aren't needed as well since they should be on that card\n"
    (at 187.96 111.76 0)
    (effects (font (size 1.27 1.27)) (justify left bottom))
  )
  (text "Capacitor cluster for pins 12,14,16,18" (at 72.39 62.23 0)
    (effects (font (size 1.27 1.27)) (justify left bottom))
  )
  (text "2280 Form Factor" (at 193.04 135.89 0)
    (effects (font (size 1.27 1.27)) (justify left bottom))
  )
  (text "Capacitor cluster for pins 2,4" (at 72.39 86.36 0)
    (effects (font (size 1.27 1.27)) (justify left bottom))
  )
  (text "Capacitor cluster for pins 70,72,74" (at 72.39 38.1 0)
    (effects (font (size 1.27 1.27)) (justify left bottom))
  )

  (global_label "PCIE_CLK_N" (shape input) (at 205.74 44.45 0) (fields_autoplaced)
    (effects (font (size 1.27 1.27)) (justify left))
    (property "Intersheetrefs" "${INTERSHEET_REFS}" (at 219.1918 44.3706 0)
      (effects (font (size 1.27 1.27)) (justify left) hide)
    )
  )
  (global_label "3V3_SSD" (shape input) (at 71.12 39.37 180) (fields_autoplaced)
    (effects (font (size 1.27 1.27)) (justify right))
    (property "Intersheetrefs" "${INTERSHEET_REFS}" (at 60.6315 39.2906 0)
      (effects (font (size 1.27 1.27)) (justify right) hide)
    )
  )
  (global_label "PCIE_RX_N" (shape output) (at 205.74 60.96 0) (fields_autoplaced)
    (effects (font (size 1.27 1.27)) (justify left))
    (property "Intersheetrefs" "${INTERSHEET_REFS}" (at 218.1032 60.8806 0)
      (effects (font (size 1.27 1.27)) (justify left) hide)
    )
  )
  (global_label "3V3_SSD" (shape input) (at 124.46 54.61 180) (fields_autoplaced)
    (effects (font (size 1.27 1.27)) (justify right))
    (property "Intersheetrefs" "${INTERSHEET_REFS}" (at 113.9715 54.6894 0)
      (effects (font (size 1.27 1.27)) (justify right) hide)
    )
  )
  (global_label "PCIE_TX_P" (shape input) (at 205.74 50.8 0) (fields_autoplaced)
    (effects (font (size 1.27 1.27)) (justify left))
    (property "Intersheetrefs" "${INTERSHEET_REFS}" (at 217.7404 50.7206 0)
      (effects (font (size 1.27 1.27)) (justify left) hide)
    )
  )
  (global_label "PCIE_CLK_P" (shape input) (at 205.74 41.91 0) (fields_autoplaced)
    (effects (font (size 1.27 1.27)) (justify left))
    (property "Intersheetrefs" "${INTERSHEET_REFS}" (at 219.1313 41.8306 0)
      (effects (font (size 1.27 1.27)) (justify left) hide)
    )
  )
  (global_label "PCIE_WAKE" (shape output) (at 124.46 66.04 180) (fields_autoplaced)
    (effects (font (size 1.27 1.27)) (justify right))
    (property "Intersheetrefs" "${INTERSHEET_REFS}" (at 111.9153 66.1194 0)
      (effects (font (size 1.27 1.27)) (justify right) hide)
    )
  )
  (global_label "3V3_SSD" (shape input) (at 71.12 63.5 180) (fields_autoplaced)
    (effects (font (size 1.27 1.27)) (justify right))
    (property "Intersheetrefs" "${INTERSHEET_REFS}" (at 60.6315 63.4206 0)
      (effects (font (size 1.27 1.27)) (justify right) hide)
    )
  )
  (global_label "PCIE_RX_P" (shape output) (at 205.74 58.42 0) (fields_autoplaced)
    (effects (font (size 1.27 1.27)) (justify left))
    (property "Intersheetrefs" "${INTERSHEET_REFS}" (at 218.0428 58.3406 0)
      (effects (font (size 1.27 1.27)) (justify left) hide)
    )
  )
  (global_label "PCIE_TX_N" (shape input) (at 205.74 53.34 0) (fields_autoplaced)
    (effects (font (size 1.27 1.27)) (justify left))
    (property "Intersheetrefs" "${INTERSHEET_REFS}" (at 217.8009 53.2606 0)
      (effects (font (size 1.27 1.27)) (justify left) hide)
    )
  )
  (global_label "PSCIE_nRST" (shape output) (at 124.46 71.12 180) (fields_autoplaced)
    (effects (font (size 1.27 1.27)) (justify right))
    (property "Intersheetrefs" "${INTERSHEET_REFS}" (at 111.0687 71.1994 0)
      (effects (font (size 1.27 1.27)) (justify right) hide)
    )
  )
  (global_label "3V3_SSD" (shape input) (at 119.38 81.28 180) (fields_autoplaced)
    (effects (font (size 1.27 1.27)) (justify right))
    (property "Intersheetrefs" "${INTERSHEET_REFS}" (at 108.8915 81.2006 0)
      (effects (font (size 1.27 1.27)) (justify right) hide)
    )
  )
  (global_label "3V3_SSD" (shape input) (at 144.78 41.91 180) (fields_autoplaced)
    (effects (font (size 1.27 1.27)) (justify right))
    (property "Intersheetrefs" "${INTERSHEET_REFS}" (at 134.2915 41.8306 0)
      (effects (font (size 1.27 1.27)) (justify right) hide)
    )
  )
  (global_label "PCIE_CLK_nREQ" (shape output) (at 124.46 68.58 180) (fields_autoplaced)
    (effects (font (size 1.27 1.27)) (justify right))
    (property "Intersheetrefs" "${INTERSHEET_REFS}" (at 107.4401 68.6594 0)
      (effects (font (size 1.27 1.27)) (justify right) hide)
    )
  )
  (global_label "3V3_SSD" (shape input) (at 71.12 87.63 180) (fields_autoplaced)
    (effects (font (size 1.27 1.27)) (justify right))
    (property "Intersheetrefs" "${INTERSHEET_REFS}" (at 60.6315 87.5506 0)
      (effects (font (size 1.27 1.27)) (justify right) hide)
    )
  )

  (symbol (lib_id "scalenode-cm4-baseboard:C_10u_0603") (at 76.2 71.12 90) (unit 1)
    (in_bom yes) (on_board yes) (dnp no)
    (property "Reference" "C2" (at 76.2 67.31 90)
      (effects (font (size 1.27 1.27) (thickness 0.15)) (justify left top))
    )
    (property "Value" "C_10u_0603" (at 86.36 50.8 0)
      (effects (font (size 1.27 1.27) (thickness 0.15)) (justify left bottom) hide)
    )
    (property "Footprint" "scalenode-cm4-baseboard-footprints:C_0603_1608Metric" (at 88.9 50.8 0)
      (effects (font (size 1.27 1.27) (thickness 0.15)) (justify left bottom) hide)
    )
    (property "Datasheet" "https://www.murata.com/products/productdetail?partno=GRM188R61A106KE69%23" (at 91.44 50.8 0)
      (effects (font (size 1.27 1.27) (thickness 0.15)) (justify left bottom) hide)
    )
    (property "Manufacturer" "Murata" (at 96.52 50.8 0)
      (effects (font (size 1.27 1.27) (thickness 0.15)) (justify left bottom) hide)
    )
    (property "MPN" "GRM188R61A106KE69D" (at 93.98 50.8 0)
      (effects (font (size 1.27 1.27) (thickness 0.15)) (justify left bottom) hide)
    )
    (property "Val" "10u" (at 76.2 69.85 90)
      (effects (font (size 1.27 1.27) (thickness 0.15)) (justify left bottom))
    )
    (property "License" "Apache-2.0" (at 99.06 50.8 0)
      (effects (font (size 1.27 1.27) (thickness 0.15)) (justify left bottom) hide)
    )
    (property "Author" "Antmicro" (at 101.6 50.8 0)
      (effects (font (size 1.27 1.27) (thickness 0.15)) (justify left bottom) hide)
    )
    (property "Voltage" "" (at 104.14 50.8 0)
      (effects (font (size 1.27 1.27)) (justify left bottom) hide)
    )
    (pin "1")
    (pin "2")
    (instances
      (project "scalenode-cm4-baseboard"
        (path ""
          (reference "C2") (unit 1)
        )
      )
    )
  )

  (symbol (lib_id "scalenode-cm4-baseboard:C_1u_0603") (at 83.82 71.12 90) (unit 1)
    (in_bom yes) (on_board yes) (dnp no)
    (property "Reference" "C5" (at 83.82 67.31 90)
      (effects (font (size 1.27 1.27) (thickness 0.15)) (justify left top))
    )
    (property "Value" "C_1u_0603" (at 93.98 50.8 0)
      (effects (font (size 1.27 1.27) (thickness 0.15)) (justify left bottom) hide)
    )
    (property "Footprint" "scalenode-cm4-baseboard-footprints:C_0603_1608Metric" (at 96.52 50.8 0)
      (effects (font (size 1.27 1.27) (thickness 0.15)) (justify left bottom) hide)
    )
    (property "Datasheet" "https://www.passivecomponent.com/wp-content/uploads/datasheet/WTC_MLCC_General_Purpose.pdf" (at 99.06 50.8 0)
      (effects (font (size 1.27 1.27) (thickness 0.15)) (justify left bottom) hide)
    )
    (property "Manufacturer" "Walsin" (at 104.14 50.8 0)
      (effects (font (size 1.27 1.27) (thickness 0.15)) (justify left bottom) hide)
    )
    (property "MPN" "0603YD105KAT2A" (at 101.6 50.8 0)
      (effects (font (size 1.27 1.27) (thickness 0.15)) (justify left bottom) hide)
    )
    (property "Val" "1u" (at 83.82 69.85 90)
      (effects (font (size 1.27 1.27) (thickness 0.15)) (justify left bottom))
    )
    (property "License" "Apache-2.0" (at 106.68 50.8 0)
      (effects (font (size 1.27 1.27) (thickness 0.15)) (justify left bottom) hide)
    )
    (property "Author" "Antmicro" (at 109.22 50.8 0)
      (effects (font (size 1.27 1.27) (thickness 0.15)) (justify left bottom) hide)
    )
    (property "Voltage" "" (at 111.76 50.8 0)
      (effects (font (size 1.27 1.27)) (justify left bottom) hide)
    )
    (property "Dielectric" "" (at 114.3 50.8 0)
      (effects (font (size 1.27 1.27)) (justify left bottom) hide)
    )
    (pin "1")
    (pin "2")
    (instances
      (project "scalenode-cm4-baseboard"
        (path ""
          (reference "C5") (unit 1)
        )
      )
    )
  )

  (symbol (lib_id "scalenode-cm4-baseboard:C_100n_0603") (at 91.44 71.12 90) (unit 1)
    (in_bom yes) (on_board yes) (dnp no)
    (property "Reference" "C8" (at 91.44 67.31 90)
      (effects (font (size 1.27 1.27) (thickness 0.15)) (justify left top))
    )
    (property "Value" "C_100n_0603" (at 101.6 50.8 0)
      (effects (font (size 1.27 1.27) (thickness 0.15)) (justify left bottom) hide)
    )
    (property "Footprint" "scalenode-cm4-baseboard-footprints:C_0603_1608Metric" (at 104.14 50.8 0)
      (effects (font (size 1.27 1.27) (thickness 0.15)) (justify left bottom) hide)
    )
    (property "Datasheet" "https://spicat.kyocera-avx.com/product/mlcc/chartview/0603YC104KAZ2A/" (at 106.68 50.8 0)
      (effects (font (size 1.27 1.27) (thickness 0.15)) (justify left bottom) hide)
    )
    (property "Manufacturer" "AVX" (at 111.76 50.8 0)
      (effects (font (size 1.27 1.27) (thickness 0.15)) (justify left bottom) hide)
    )
    (property "MPN" "0603YC104KAZ2A" (at 109.22 50.8 0)
      (effects (font (size 1.27 1.27) (thickness 0.15)) (justify left bottom) hide)
    )
    (property "Val" "100n" (at 91.44 69.85 90)
      (effects (font (size 1.27 1.27) (thickness 0.15)) (justify left bottom))
    )
    (property "License" "Apache-2.0" (at 114.3 50.8 0)
      (effects (font (size 1.27 1.27) (thickness 0.15)) (justify left bottom) hide)
    )
    (property "Author" "Antmicro" (at 116.84 50.8 0)
      (effects (font (size 1.27 1.27) (thickness 0.15)) (justify left bottom) hide)
    )
    (property "Voltage" "" (at 119.38 50.8 0)
      (effects (font (size 1.27 1.27)) (justify left bottom) hide)
    )
    (property "Dielectric" "" (at 121.92 50.8 0)
      (effects (font (size 1.27 1.27)) (justify left bottom) hide)
    )
    (pin "1")
    (pin "2")
    (instances
      (project "scalenode-cm4-baseboard"
        (path ""
          (reference "C8") (unit 1)
        )
      )
    )
  )

  (symbol (lib_id "scalenode-cm4-baseboard:C_1n_0603") (at 99.06 71.12 90) (unit 1)
    (in_bom yes) (on_board yes) (dnp no)
    (property "Reference" "C11" (at 99.06 67.31 90)
      (effects (font (size 1.27 1.27) (thickness 0.15)) (justify left top))
    )
    (property "Value" "C_1n_0603" (at 109.22 50.8 0)
      (effects (font (size 1.27 1.27) (thickness 0.15)) (justify left bottom) hide)
    )
    (property "Footprint" "scalenode-cm4-baseboard-footprints:C_0603_1608Metric" (at 111.76 50.8 0)
      (effects (font (size 1.27 1.27) (thickness 0.15)) (justify left bottom) hide)
    )
    (property "Datasheet" "https://spicat.kyocera-avx.com/product/mlcc/chartview/06031C102JAT2A/" (at 114.3 50.8 0)
      (effects (font (size 1.27 1.27) (thickness 0.15)) (justify left bottom) hide)
    )
    (property "Manufacturer" "AVX" (at 119.38 50.8 0)
      (effects (font (size 1.27 1.27) (thickness 0.15)) (justify left bottom) hide)
    )
    (property "MPN" "06031C102JAT2A" (at 116.84 50.8 0)
      (effects (font (size 1.27 1.27) (thickness 0.15)) (justify left bottom) hide)
    )
    (property "Val" "1n" (at 99.06 69.85 90)
      (effects (font (size 1.27 1.27) (thickness 0.15)) (justify left bottom))
    )
    (property "License" "Apache-2.0" (at 121.92 50.8 0)
      (effects (font (size 1.27 1.27) (thickness 0.15)) (justify left bottom) hide)
    )
    (property "Author" "Antmicro" (at 124.46 50.8 0)
      (effects (font (size 1.27 1.27) (thickness 0.15)) (justify left bottom) hide)
    )
    (property "Voltage" "" (at 127 50.8 0)
      (effects (font (size 1.27 1.27)) (justify left bottom) hide)
    )
    (property "Dielectric" "" (at 129.54 50.8 0)
      (effects (font (size 1.27 1.27)) (justify left bottom) hide)
    )
    (pin "1")
    (pin "2")
    (instances
      (project "scalenode-cm4-baseboard"
        (path ""
          (reference "C11") (unit 1)
        )
      )
    )
  )

  (symbol (lib_id "scalenode-cm4-baseboard:C_10u_0603") (at 76.2 95.25 90) (unit 1)
    (in_bom yes) (on_board yes) (dnp no)
    (property "Reference" "C3" (at 76.2 91.44 90)
      (effects (font (size 1.27 1.27) (thickness 0.15)) (justify left top))
    )
    (property "Value" "C_10u_0603" (at 86.36 74.93 0)
      (effects (font (size 1.27 1.27) (thickness 0.15)) (justify left bottom) hide)
    )
    (property "Footprint" "scalenode-cm4-baseboard-footprints:C_0603_1608Metric" (at 88.9 74.93 0)
      (effects (font (size 1.27 1.27) (thickness 0.15)) (justify left bottom) hide)
    )
    (property "Datasheet" "https://www.murata.com/products/productdetail?partno=GRM188R61A106KE69%23" (at 91.44 74.93 0)
      (effects (font (size 1.27 1.27) (thickness 0.15)) (justify left bottom) hide)
    )
    (property "Manufacturer" "Murata" (at 96.52 74.93 0)
      (effects (font (size 1.27 1.27) (thickness 0.15)) (justify left bottom) hide)
    )
    (property "MPN" "GRM188R61A106KE69D" (at 93.98 74.93 0)
      (effects (font (size 1.27 1.27) (thickness 0.15)) (justify left bottom) hide)
    )
    (property "Val" "10u" (at 76.2 93.98 90)
      (effects (font (size 1.27 1.27) (thickness 0.15)) (justify left bottom))
    )
    (property "License" "Apache-2.0" (at 99.06 74.93 0)
      (effects (font (size 1.27 1.27) (thickness 0.15)) (justify left bottom) hide)
    )
    (property "Author" "Antmicro" (at 101.6 74.93 0)
      (effects (font (size 1.27 1.27) (thickness 0.15)) (justify left bottom) hide)
    )
    (property "Voltage" "" (at 104.14 74.93 0)
      (effects (font (size 1.27 1.27)) (justify left bottom) hide)
    )
    (pin "1")
    (pin "2")
    (instances
      (project "scalenode-cm4-baseboard"
        (path ""
          (reference "C3") (unit 1)
        )
      )
    )
  )

  (symbol (lib_id "scalenode-cm4-baseboard:C_1u_0603") (at 83.82 95.25 90) (unit 1)
    (in_bom yes) (on_board yes) (dnp no)
    (property "Reference" "C6" (at 83.82 91.44 90)
      (effects (font (size 1.27 1.27) (thickness 0.15)) (justify left top))
    )
    (property "Value" "C_1u_0603" (at 93.98 74.93 0)
      (effects (font (size 1.27 1.27) (thickness 0.15)) (justify left bottom) hide)
    )
    (property "Footprint" "scalenode-cm4-baseboard-footprints:C_0603_1608Metric" (at 96.52 74.93 0)
      (effects (font (size 1.27 1.27) (thickness 0.15)) (justify left bottom) hide)
    )
    (property "Datasheet" "https://www.passivecomponent.com/wp-content/uploads/datasheet/WTC_MLCC_General_Purpose.pdf" (at 99.06 74.93 0)
      (effects (font (size 1.27 1.27) (thickness 0.15)) (justify left bottom) hide)
    )
    (property "Manufacturer" "Walsin" (at 104.14 74.93 0)
      (effects (font (size 1.27 1.27) (thickness 0.15)) (justify left bottom) hide)
    )
    (property "MPN" "0603YD105KAT2A" (at 101.6 74.93 0)
      (effects (font (size 1.27 1.27) (thickness 0.15)) (justify left bottom) hide)
    )
    (property "Val" "1u" (at 83.82 93.98 90)
      (effects (font (size 1.27 1.27) (thickness 0.15)) (justify left bottom))
    )
    (property "License" "Apache-2.0" (at 106.68 74.93 0)
      (effects (font (size 1.27 1.27) (thickness 0.15)) (justify left bottom) hide)
    )
    (property "Author" "Antmicro" (at 109.22 74.93 0)
      (effects (font (size 1.27 1.27) (thickness 0.15)) (justify left bottom) hide)
    )
    (property "Voltage" "" (at 111.76 74.93 0)
      (effects (font (size 1.27 1.27)) (justify left bottom) hide)
    )
    (property "Dielectric" "" (at 114.3 74.93 0)
      (effects (font (size 1.27 1.27)) (justify left bottom) hide)
    )
    (pin "1")
    (pin "2")
    (instances
      (project "scalenode-cm4-baseboard"
        (path ""
          (reference "C6") (unit 1)
        )
      )
    )
  )

  (symbol (lib_id "scalenode-cm4-baseboard:C_100n_0603") (at 91.44 95.25 90) (unit 1)
    (in_bom yes) (on_board yes) (dnp no)
    (property "Reference" "C9" (at 91.44 91.44 90)
      (effects (font (size 1.27 1.27) (thickness 0.15)) (justify left top))
    )
    (property "Value" "C_100n_0603" (at 101.6 74.93 0)
      (effects (font (size 1.27 1.27) (thickness 0.15)) (justify left bottom) hide)
    )
    (property "Footprint" "scalenode-cm4-baseboard-footprints:C_0603_1608Metric" (at 104.14 74.93 0)
      (effects (font (size 1.27 1.27) (thickness 0.15)) (justify left bottom) hide)
    )
    (property "Datasheet" "https://spicat.kyocera-avx.com/product/mlcc/chartview/0603YC104KAZ2A/" (at 106.68 74.93 0)
      (effects (font (size 1.27 1.27) (thickness 0.15)) (justify left bottom) hide)
    )
    (property "Manufacturer" "AVX" (at 111.76 74.93 0)
      (effects (font (size 1.27 1.27) (thickness 0.15)) (justify left bottom) hide)
    )
    (property "MPN" "0603YC104KAZ2A" (at 109.22 74.93 0)
      (effects (font (size 1.27 1.27) (thickness 0.15)) (justify left bottom) hide)
    )
    (property "Val" "100n" (at 91.44 93.98 90)
      (effects (font (size 1.27 1.27) (thickness 0.15)) (justify left bottom))
    )
    (property "License" "Apache-2.0" (at 114.3 74.93 0)
      (effects (font (size 1.27 1.27) (thickness 0.15)) (justify left bottom) hide)
    )
    (property "Author" "Antmicro" (at 116.84 74.93 0)
      (effects (font (size 1.27 1.27) (thickness 0.15)) (justify left bottom) hide)
    )
    (property "Voltage" "" (at 119.38 74.93 0)
      (effects (font (size 1.27 1.27)) (justify left bottom) hide)
    )
    (property "Dielectric" "" (at 121.92 74.93 0)
      (effects (font (size 1.27 1.27)) (justify left bottom) hide)
    )
    (pin "1")
    (pin "2")
    (instances
      (project "scalenode-cm4-baseboard"
        (path ""
          (reference "C9") (unit 1)
        )
      )
    )
  )

  (symbol (lib_id "scalenode-cm4-baseboard:C_1n_0603") (at 99.06 95.25 90) (unit 1)
    (in_bom yes) (on_board yes) (dnp no)
    (property "Reference" "C12" (at 99.06 91.44 90)
      (effects (font (size 1.27 1.27) (thickness 0.15)) (justify left top))
    )
    (property "Value" "C_1n_0603" (at 109.22 74.93 0)
      (effects (font (size 1.27 1.27) (thickness 0.15)) (justify left bottom) hide)
    )
    (property "Footprint" "scalenode-cm4-baseboard-footprints:C_0603_1608Metric" (at 111.76 74.93 0)
      (effects (font (size 1.27 1.27) (thickness 0.15)) (justify left bottom) hide)
    )
    (property "Datasheet" "https://spicat.kyocera-avx.com/product/mlcc/chartview/06031C102JAT2A/" (at 114.3 74.93 0)
      (effects (font (size 1.27 1.27) (thickness 0.15)) (justify left bottom) hide)
    )
    (property "Manufacturer" "AVX" (at 119.38 74.93 0)
      (effects (font (size 1.27 1.27) (thickness 0.15)) (justify left bottom) hide)
    )
    (property "MPN" "06031C102JAT2A" (at 116.84 74.93 0)
      (effects (font (size 1.27 1.27) (thickness 0.15)) (justify left bottom) hide)
    )
    (property "Val" "1n" (at 99.06 93.98 90)
      (effects (font (size 1.27 1.27) (thickness 0.15)) (justify left bottom))
    )
    (property "License" "Apache-2.0" (at 121.92 74.93 0)
      (effects (font (size 1.27 1.27) (thickness 0.15)) (justify left bottom) hide)
    )
    (property "Author" "Antmicro" (at 124.46 74.93 0)
      (effects (font (size 1.27 1.27) (thickness 0.15)) (justify left bottom) hide)
    )
    (property "Voltage" "" (at 127 74.93 0)
      (effects (font (size 1.27 1.27)) (justify left bottom) hide)
    )
    (property "Dielectric" "" (at 129.54 74.93 0)
      (effects (font (size 1.27 1.27)) (justify left bottom) hide)
    )
    (pin "1")
    (pin "2")
    (instances
      (project "scalenode-cm4-baseboard"
        (path ""
          (reference "C12") (unit 1)
        )
      )
    )
  )

  (symbol (lib_id "scalenode-cm4-baseboard:C_10u_0603") (at 76.2 46.99 90) (unit 1)
    (in_bom yes) (on_board yes) (dnp no)
    (property "Reference" "C1" (at 76.2 43.18 90)
      (effects (font (size 1.27 1.27) (thickness 0.15)) (justify left top))
    )
    (property "Value" "C_10u_0603" (at 86.36 26.67 0)
      (effects (font (size 1.27 1.27) (thickness 0.15)) (justify left bottom) hide)
    )
    (property "Footprint" "scalenode-cm4-baseboard-footprints:C_0603_1608Metric" (at 88.9 26.67 0)
      (effects (font (size 1.27 1.27) (thickness 0.15)) (justify left bottom) hide)
    )
    (property "Datasheet" "https://www.murata.com/products/productdetail?partno=GRM188R61A106KE69%23" (at 91.44 26.67 0)
      (effects (font (size 1.27 1.27) (thickness 0.15)) (justify left bottom) hide)
    )
    (property "Manufacturer" "Murata" (at 96.52 26.67 0)
      (effects (font (size 1.27 1.27) (thickness 0.15)) (justify left bottom) hide)
    )
    (property "MPN" "GRM188R61A106KE69D" (at 93.98 26.67 0)
      (effects (font (size 1.27 1.27) (thickness 0.15)) (justify left bottom) hide)
    )
    (property "Val" "10u" (at 76.2 45.72 90)
      (effects (font (size 1.27 1.27) (thickness 0.15)) (justify left bottom))
    )
    (property "License" "Apache-2.0" (at 99.06 26.67 0)
      (effects (font (size 1.27 1.27) (thickness 0.15)) (justify left bottom) hide)
    )
    (property "Author" "Antmicro" (at 101.6 26.67 0)
      (effects (font (size 1.27 1.27) (thickness 0.15)) (justify left bottom) hide)
    )
    (property "Voltage" "" (at 104.14 26.67 0)
      (effects (font (size 1.27 1.27)) (justify left bottom) hide)
    )
    (pin "1")
    (pin "2")
    (instances
      (project "scalenode-cm4-baseboard"
        (path ""
          (reference "C1") (unit 1)
        )
      )
    )
  )

  (symbol (lib_id "scalenode-cm4-baseboard:C_1u_0603") (at 83.82 46.99 90) (unit 1)
    (in_bom yes) (on_board yes) (dnp no)
    (property "Reference" "C4" (at 83.82 43.18 90)
      (effects (font (size 1.27 1.27) (thickness 0.15)) (justify left top))
    )
    (property "Value" "C_1u_0603" (at 93.98 26.67 0)
      (effects (font (size 1.27 1.27) (thickness 0.15)) (justify left bottom) hide)
    )
    (property "Footprint" "scalenode-cm4-baseboard-footprints:C_0603_1608Metric" (at 96.52 26.67 0)
      (effects (font (size 1.27 1.27) (thickness 0.15)) (justify left bottom) hide)
    )
    (property "Datasheet" "https://www.passivecomponent.com/wp-content/uploads/datasheet/WTC_MLCC_General_Purpose.pdf" (at 99.06 26.67 0)
      (effects (font (size 1.27 1.27) (thickness 0.15)) (justify left bottom) hide)
    )
    (property "Manufacturer" "Walsin" (at 104.14 26.67 0)
      (effects (font (size 1.27 1.27) (thickness 0.15)) (justify left bottom) hide)
    )
    (property "MPN" "0603YD105KAT2A" (at 101.6 26.67 0)
      (effects (font (size 1.27 1.27) (thickness 0.15)) (justify left bottom) hide)
    )
    (property "Val" "1u" (at 83.82 45.72 90)
      (effects (font (size 1.27 1.27) (thickness 0.15)) (justify left bottom))
    )
    (property "License" "Apache-2.0" (at 106.68 26.67 0)
      (effects (font (size 1.27 1.27) (thickness 0.15)) (justify left bottom) hide)
    )
    (property "Author" "Antmicro" (at 109.22 26.67 0)
      (effects (font (size 1.27 1.27) (thickness 0.15)) (justify left bottom) hide)
    )
    (property "Voltage" "" (at 111.76 26.67 0)
      (effects (font (size 1.27 1.27)) (justify left bottom) hide)
    )
    (property "Dielectric" "" (at 114.3 26.67 0)
      (effects (font (size 1.27 1.27)) (justify left bottom) hide)
    )
    (pin "1")
    (pin "2")
    (instances
      (project "scalenode-cm4-baseboard"
        (path ""
          (reference "C4") (unit 1)
        )
      )
    )
  )

  (symbol (lib_id "scalenode-cm4-baseboard:C_100n_0603") (at 91.44 46.99 90) (unit 1)
    (in_bom yes) (on_board yes) (dnp no)
    (property "Reference" "C7" (at 91.44 43.18 90)
      (effects (font (size 1.27 1.27) (thickness 0.15)) (justify left top))
    )
    (property "Value" "C_100n_0603" (at 101.6 26.67 0)
      (effects (font (size 1.27 1.27) (thickness 0.15)) (justify left bottom) hide)
    )
    (property "Footprint" "scalenode-cm4-baseboard-footprints:C_0603_1608Metric" (at 104.14 26.67 0)
      (effects (font (size 1.27 1.27) (thickness 0.15)) (justify left bottom) hide)
    )
    (property "Datasheet" "https://spicat.kyocera-avx.com/product/mlcc/chartview/0603YC104KAZ2A/" (at 106.68 26.67 0)
      (effects (font (size 1.27 1.27) (thickness 0.15)) (justify left bottom) hide)
    )
    (property "Manufacturer" "AVX" (at 111.76 26.67 0)
      (effects (font (size 1.27 1.27) (thickness 0.15)) (justify left bottom) hide)
    )
    (property "MPN" "0603YC104KAZ2A" (at 109.22 26.67 0)
      (effects (font (size 1.27 1.27) (thickness 0.15)) (justify left bottom) hide)
    )
    (property "Val" "100n" (at 91.44 45.72 90)
      (effects (font (size 1.27 1.27) (thickness 0.15)) (justify left bottom))
    )
    (property "License" "Apache-2.0" (at 114.3 26.67 0)
      (effects (font (size 1.27 1.27) (thickness 0.15)) (justify left bottom) hide)
    )
    (property "Author" "Antmicro" (at 116.84 26.67 0)
      (effects (font (size 1.27 1.27) (thickness 0.15)) (justify left bottom) hide)
    )
    (property "Voltage" "" (at 119.38 26.67 0)
      (effects (font (size 1.27 1.27)) (justify left bottom) hide)
    )
    (property "Dielectric" "" (at 121.92 26.67 0)
      (effects (font (size 1.27 1.27)) (justify left bottom) hide)
    )
    (pin "1")
    (pin "2")
    (instances
      (project "scalenode-cm4-baseboard"
        (path ""
          (reference "C7") (unit 1)
        )
      )
    )
  )

  (symbol (lib_id "scalenode-cm4-baseboard:C_1n_0603") (at 99.06 46.99 90) (unit 1)
    (in_bom yes) (on_board yes) (dnp no)
    (property "Reference" "C10" (at 99.06 43.18 90)
      (effects (font (size 1.27 1.27) (thickness 0.15)) (justify left top))
    )
    (property "Value" "C_1n_0603" (at 109.22 26.67 0)
      (effects (font (size 1.27 1.27) (thickness 0.15)) (justify left bottom) hide)
    )
    (property "Footprint" "scalenode-cm4-baseboard-footprints:C_0603_1608Metric" (at 111.76 26.67 0)
      (effects (font (size 1.27 1.27) (thickness 0.15)) (justify left bottom) hide)
    )
    (property "Datasheet" "https://spicat.kyocera-avx.com/product/mlcc/chartview/06031C102JAT2A/" (at 114.3 26.67 0)
      (effects (font (size 1.27 1.27) (thickness 0.15)) (justify left bottom) hide)
    )
    (property "Manufacturer" "AVX" (at 119.38 26.67 0)
      (effects (font (size 1.27 1.27) (thickness 0.15)) (justify left bottom) hide)
    )
    (property "MPN" "06031C102JAT2A" (at 116.84 26.67 0)
      (effects (font (size 1.27 1.27) (thickness 0.15)) (justify left bottom) hide)
    )
    (property "Val" "1n" (at 99.06 45.72 90)
      (effects (font (size 1.27 1.27) (thickness 0.15)) (justify left bottom))
    )
    (property "License" "Apache-2.0" (at 121.92 26.67 0)
      (effects (font (size 1.27 1.27) (thickness 0.15)) (justify left bottom) hide)
    )
    (property "Author" "Antmicro" (at 124.46 26.67 0)
      (effects (font (size 1.27 1.27) (thickness 0.15)) (justify left bottom) hide)
    )
    (property "Voltage" "" (at 127 26.67 0)
      (effects (font (size 1.27 1.27)) (justify left bottom) hide)
    )
    (property "Dielectric" "" (at 129.54 26.67 0)
      (effects (font (size 1.27 1.27)) (justify left bottom) hide)
    )
    (pin "1")
    (pin "2")
    (instances
      (project "scalenode-cm4-baseboard"
        (path ""
          (reference "C10") (unit 1)
        )
      )
    )
  )

  (symbol (lib_id "scalenode-cm4-baseboard:GND") (at 99.06 53.34 0) (unit 1)
    (in_bom yes) (on_board yes) (dnp no) (fields_autoplaced)
    (property "Reference" "#PWR04" (at 107.95 55.88 0)
      (effects (font (size 1.27 1.27) (thickness 0.15)) (justify left bottom) hide)
    )
    (property "Value" "GND" (at 97.0498 58.42 0)
      (effects (font (size 1.27 1.27) (thickness 0.15)) (justify left bottom))
    )
    (property "Footprint" "" (at 107.95 60.96 0)
      (effects (font (size 1.27 1.27) (thickness 0.15)) (justify left bottom) hide)
    )
    (property "Datasheet" "" (at 107.95 66.04 0)
      (effects (font (size 1.27 1.27) (thickness 0.15)) (justify left bottom) hide)
    )
    (property "Author" "Antmicro" (at 107.95 60.96 0)
      (effects (font (size 1.27 1.27) (thickness 0.15)) (justify left bottom) hide)
    )
    (property "License" "Apache-2.0" (at 107.95 63.5 0)
      (effects (font (size 1.27 1.27) (thickness 0.15)) (justify left bottom) hide)
    )
    (pin "1")
    (instances
      (project "scalenode-cm4-baseboard"
        (path ""
          (reference "#PWR04") (unit 1)
        )
      )
    )
  )

  (symbol (lib_id "scalenode-cm4-baseboard:GND") (at 99.06 77.47 0) (unit 1)
    (in_bom yes) (on_board yes) (dnp no) (fields_autoplaced)
    (property "Reference" "#PWR05" (at 107.95 80.01 0)
      (effects (font (size 1.27 1.27) (thickness 0.15)) (justify left bottom) hide)
    )
    (property "Value" "GND" (at 97.0498 82.55 0)
      (effects (font (size 1.27 1.27) (thickness 0.15)) (justify left bottom))
    )
    (property "Footprint" "" (at 107.95 85.09 0)
      (effects (font (size 1.27 1.27) (thickness 0.15)) (justify left bottom) hide)
    )
    (property "Datasheet" "" (at 107.95 90.17 0)
      (effects (font (size 1.27 1.27) (thickness 0.15)) (justify left bottom) hide)
    )
    (property "Author" "Antmicro" (at 107.95 85.09 0)
      (effects (font (size 1.27 1.27) (thickness 0.15)) (justify left bottom) hide)
    )
    (property "License" "Apache-2.0" (at 107.95 87.63 0)
      (effects (font (size 1.27 1.27) (thickness 0.15)) (justify left bottom) hide)
    )
    (pin "1")
    (instances
      (project "scalenode-cm4-baseboard"
        (path ""
          (reference "#PWR05") (unit 1)
        )
      )
    )
  )

  (symbol (lib_id "scalenode-cm4-baseboard:GND") (at 99.06 101.6 0) (unit 1)
    (in_bom yes) (on_board yes) (dnp no) (fields_autoplaced)
    (property "Reference" "#PWR06" (at 107.95 104.14 0)
      (effects (font (size 1.27 1.27) (thickness 0.15)) (justify left bottom) hide)
    )
    (property "Value" "GND" (at 97.0498 106.68 0)
      (effects (font (size 1.27 1.27) (thickness 0.15)) (justify left bottom))
    )
    (property "Footprint" "" (at 107.95 109.22 0)
      (effects (font (size 1.27 1.27) (thickness 0.15)) (justify left bottom) hide)
    )
    (property "Datasheet" "" (at 107.95 114.3 0)
      (effects (font (size 1.27 1.27) (thickness 0.15)) (justify left bottom) hide)
    )
    (property "Author" "Antmicro" (at 107.95 109.22 0)
      (effects (font (size 1.27 1.27) (thickness 0.15)) (justify left bottom) hide)
    )
    (property "License" "Apache-2.0" (at 107.95 111.76 0)
      (effects (font (size 1.27 1.27) (thickness 0.15)) (justify left bottom) hide)
    )
    (pin "1")
    (instances
      (project "scalenode-cm4-baseboard"
        (path ""
          (reference "#PWR06") (unit 1)
        )
      )
    )
  )

  (symbol (lib_id "scalenode-cm4-baseboard:Spacer_Drill1mm_H4mm_97730406332R") (at 190.5 127 0) (unit 1)
    (in_bom no) (on_board yes) (dnp yes)
    (property "Reference" "SP1" (at 199.39 127 0)
      (effects (font (size 1.27 1.27) (thickness 0.15)) (justify left bottom))
    )
    (property "Value" "Spacer_Drill1mm_H4mm_97730406332R" (at 199.39 129.54 0)
      (effects (font (size 1.27 1.27) (thickness 0.15)) (justify left bottom) hide)
    )
    (property "Footprint" "scalenode-cm4-baseboard-footprints:Spacer_Drill1mm_H4mm_97730406332R" (at 205.74 139.7 0)
      (effects (font (size 1.27 1.27) (thickness 0.15)) (justify left bottom) hide)
    )
    (property "Datasheet" "https://www.we-online.com/components/products/datasheet/97730406332R.pdf" (at 205.74 142.24 0)
      (effects (font (size 1.27 1.27) (thickness 0.15)) (justify left bottom) hide)
    )
    (property "Manufacturer" "Würth Elektronik" (at 213.36 139.7 0)
      (effects (font (size 1.27 1.27) (thickness 0.15)) (justify left bottom) hide)
    )
    (property "MPN" "97730406332R " (at 212.09 123.19 0)
      (effects (font (size 1.27 1.27) (thickness 0.15)) (justify left bottom))
    )
    (property "DNP" "DNP" (at 195.58 130.81 0)
      (effects (font (size 1 1)))
    )
    (property "Author" "Antmicro" (at 205.74 144.78 0)
      (effects (font (size 1.27 1.27) (thickness 0.15)) (justify left bottom) hide)
    )
    (property "License" "Apache-2.0" (at 205.74 147.32 0)
      (effects (font (size 1.27 1.27) (thickness 0.15)) (justify left bottom) hide)
    )
    (pin "1")
    (instances
      (project "scalenode-cm4-baseboard"
        (path ""
          (reference "SP1") (unit 1)
        )
      )
    )
  )

  (symbol (lib_id "scalenode-cm4-baseboard:Spacer_Drill1mm_H4mm_97730406332R") (at 190.5 139.7 0) (unit 1)
    (in_bom yes) (on_board yes) (dnp no)
    (property "Reference" "SP6" (at 199.39 139.7 0)
      (effects (font (size 1.27 1.27) (thickness 0.15)) (justify left bottom))
    )
    (property "Value" "Spacer_Drill1mm_H4mm_97730406332R" (at 199.39 142.24 0)
      (effects (font (size 1.27 1.27) (thickness 0.15)) (justify left bottom) hide)
    )
    (property "Footprint" "scalenode-cm4-baseboard-footprints:Spacer_Drill1mm_H4mm_97730406332R" (at 205.74 152.4 0)
      (effects (font (size 1.27 1.27) (thickness 0.15)) (justify left bottom) hide)
    )
    (property "Datasheet" "https://www.we-online.com/components/products/datasheet/97730406332R.pdf" (at 205.74 154.94 0)
      (effects (font (size 1.27 1.27) (thickness 0.15)) (justify left bottom) hide)
    )
    (property "Manufacturer" "Würth Elektronik" (at 213.36 152.4 0)
      (effects (font (size 1.27 1.27) (thickness 0.15)) (justify left bottom) hide)
    )
    (property "MPN" "97730406332R " (at 212.09 135.89 0)
      (effects (font (size 1.27 1.27) (thickness 0.15)) (justify left bottom))
    )
    (property "Author" "Antmicro" (at 205.74 157.48 0)
      (effects (font (size 1.27 1.27) (thickness 0.15)) (justify left bottom) hide)
    )
    (property "License" "Apache-2.0" (at 205.74 160.02 0)
      (effects (font (size 1.27 1.27) (thickness 0.15)) (justify left bottom) hide)
    )
    (pin "1")
    (instances
      (project "scalenode-cm4-baseboard"
        (path ""
          (reference "SP6") (unit 1)
        )
      )
    )
  )

  (symbol (lib_id "scalenode-cm4-baseboard:LED_G_0603_598-8D80-107F") (at 130.81 81.28 0) (unit 1)
    (in_bom yes) (on_board yes) (dnp no)
    (property "Reference" "D1" (at 133.35 85.09 0)
      (effects (font (size 1.27 1.27) (thickness 0.15)) (justify left bottom))
    )
    (property "Value" "LED_G_0603_598-8D80-107F" (at 125.73 78.74 0)
      (effects (font (size 1.27 1.27) (thickness 0.15)) (justify left bottom) hide)
    )
    (property "Footprint" "scalenode-cm4-baseboard-footprints:LED_0603_1608Metric_G" (at 153.67 88.9 0)
      (effects (font (size 1.27 1.27) (thickness 0.15)) (justify left bottom) hide)
    )
    (property "Datasheet" "https://www.farnell.com/datasheets/3093797.pdf" (at 153.67 91.44 0)
      (effects (font (size 1.27 1.27) (thickness 0.15)) (justify left bottom) hide)
    )
    (property "MPN" "598-8D80-107F" (at 153.67 93.98 0)
      (effects (font (size 1.27 1.27) (thickness 0.15)) (justify left bottom) hide)
    )
    (property "Manufacturer" "Dialight" (at 153.67 96.52 0)
      (effects (font (size 1.27 1.27) (thickness 0.15)) (justify left bottom) hide)
    )
    (property "Author" "Antmicro" (at 153.67 99.06 0)
      (effects (font (size 1.27 1.27) (thickness 0.15)) (justify left bottom) hide)
    )
    (property "License" "Apache-2.0" (at 153.67 101.6 0)
      (effects (font (size 1.27 1.27) (thickness 0.15)) (justify left bottom) hide)
    )
    (pin "1")
    (pin "2")
    (instances
      (project "scalenode-cm4-baseboard"
        (path ""
          (reference "D1") (unit 1)
        )
      )
    )
  )

  (symbol (lib_id "scalenode-cm4-baseboard:GND") (at 144.78 107.95 0) (unit 1)
    (in_bom yes) (on_board yes) (dnp no) (fields_autoplaced)
    (property "Reference" "#PWR0120" (at 153.67 110.49 0)
      (effects (font (size 1.27 1.27) (thickness 0.15)) (justify left bottom) hide)
    )
    (property "Value" "GND" (at 142.7698 113.03 0)
      (effects (font (size 1.27 1.27) (thickness 0.15)) (justify left bottom))
    )
    (property "Footprint" "" (at 153.67 115.57 0)
      (effects (font (size 1.27 1.27) (thickness 0.15)) (justify left bottom) hide)
    )
    (property "Datasheet" "" (at 153.67 120.65 0)
      (effects (font (size 1.27 1.27) (thickness 0.15)) (justify left bottom) hide)
    )
    (property "Author" "Antmicro" (at 153.67 115.57 0)
      (effects (font (size 1.27 1.27) (thickness 0.15)) (justify left bottom) hide)
    )
    (property "License" "Apache-2.0" (at 153.67 118.11 0)
      (effects (font (size 1.27 1.27) (thickness 0.15)) (justify left bottom) hide)
    )
    (pin "1")
    (instances
      (project "scalenode-cm4-baseboard"
        (path ""
          (reference "#PWR0120") (unit 1)
        )
      )
    )
  )

  (symbol (lib_id "scalenode-cm4-baseboard:Bus_M.2_MDT580M01001") (at 146.05 41.91 0) (unit 1)
    (in_bom yes) (on_board yes) (dnp no) (fields_autoplaced)
    (property "Reference" "J3" (at 165.1 34.29 0)
      (effects (font (size 1.27 1.27) (thickness 0.15)))
    )
    (property "Value" "Bus_M.2_MDT580M01001" (at 165.1 36.83 0)
      (effects (font (size 1.27 1.27) (thickness 0.15)))
    )
    (property "Footprint" "scalenode-cm4-baseboard-footprints:Bus_M.2_Socket_Key_M_Amphenol_MDT580M01001" (at 198.12 49.53 0)
      (effects (font (size 1.27 1.27) (thickness 0.15)) (justify left bottom) hide)
    )
    (property "Datasheet" "https://cdn.amphenol-cs.com/media/wysiwyg/files/documentation/gs-12-1248.pdf" (at 198.12 52.07 0)
      (effects (font (size 1.27 1.27) (thickness 0.15)) (justify left bottom) hide)
    )
    (property "MPN" "MDT580M01001" (at 198.12 54.61 0)
      (effects (font (size 1.27 1.27) (thickness 0.15)) (justify left bottom) hide)
    )
    (property "Manufacturer" "Amphenol" (at 198.12 57.15 0)
      (effects (font (size 1.27 1.27) (thickness 0.15)) (justify left bottom) hide)
    )
    (property "Author" "Antmicro" (at 198.12 59.69 0)
      (effects (font (size 1.27 1.27) (thickness 0.15)) (justify left bottom) hide)
    )
    (property "License" "Apache-2.0" (at 198.12 62.23 0)
      (effects (font (size 1.27 1.27) (thickness 0.15)) (justify left bottom) hide)
    )
    (pin "1")
    (pin "10")
    (pin "11")
    (pin "12")
    (pin "13")
    (pin "14")
    (pin "15")
    (pin "16")
    (pin "17")
    (pin "18")
    (pin "19")
    (pin "2")
    (pin "20")
    (pin "21")
    (pin "22")
    (pin "23")
    (pin "24")
    (pin "25")
    (pin "26")
    (pin "27")
    (pin "28")
    (pin "29")
    (pin "3")
    (pin "30")
    (pin "31")
    (pin "32")
    (pin "33")
    (pin "34")
    (pin "35")
    (pin "36")
    (pin "37")
    (pin "38")
    (pin "39")
    (pin "4")
    (pin "40")
    (pin "41")
    (pin "42")
    (pin "43")
    (pin "44")
    (pin "45")
    (pin "46")
    (pin "47")
    (pin "48")
    (pin "49")
    (pin "5")
    (pin "50")
    (pin "51")
    (pin "52")
    (pin "53")
    (pin "54")
    (pin "55")
    (pin "56")
    (pin "57")
    (pin "58")
    (pin "6")
    (pin "67")
    (pin "68")
    (pin "69")
    (pin "7")
    (pin "70")
    (pin "71")
    (pin "72")
    (pin "73")
    (pin "74")
    (pin "75")
    (pin "8")
    (pin "9")
    (pin "SH1")
    (pin "SH2")
    (instances
      (project "scalenode-cm4-baseboard"
        (path ""
          (reference "J3") (unit 1)
        )
      )
    )
  )

  (symbol (lib_id "scalenode-cm4-baseboard:R_270R_0603") (at 127 81.28 180) (unit 1)
    (in_bom yes) (on_board yes) (dnp no)
    (property "Reference" "R2" (at 125.73 77.47 0)
      (effects (font (size 1.27 1.27) (thickness 0.15)) (justify left bottom))
    )
    (property "Value" "R_270R_0603" (at 106.68 68.58 0)
      (effects (font (size 1.27 1.27) (thickness 0.15)) (justify left bottom) hide)
    )
    (property "Footprint" "scalenode-cm4-baseboard-footprints:R_0603_1608Metric" (at 106.68 66.04 0)
      (effects (font (size 1.27 1.27) (thickness 0.15)) (justify left bottom) hide)
    )
    (property "Datasheet" "https://www.bourns.com/docs/product-datasheets/cr.pdf" (at 106.68 63.5 0)
      (effects (font (size 1.27 1.27) (thickness 0.15)) (justify left bottom) hide)
    )
    (property "Manufacturer" "Bourns" (at 106.68 58.42 0)
      (effects (font (size 1.27 1.27) (thickness 0.15)) (justify left bottom) hide)
    )
    (property "MPN" "CR0603-FX-2700ELF" (at 106.68 60.96 0)
      (effects (font (size 1.27 1.27) (thickness 0.15)) (justify left bottom) hide)
    )
    (property "Val" "270R" (at 127 82.55 0)
      (effects (font (size 1.27 1.27) (thickness 0.15)) (justify left bottom))
    )
    (property "License" "Apache-2.0" (at 106.68 55.88 0)
      (effects (font (size 1.27 1.27) (thickness 0.15)) (justify left bottom) hide)
    )
    (property "Author" "Antmicro" (at 106.68 53.34 0)
      (effects (font (size 1.27 1.27) (thickness 0.15)) (justify left bottom) hide)
    )
    (property "Tolerance" "1%" (at 106.68 71.12 0)
      (effects (font (size 1.27 1.27)) (justify left bottom) hide)
    )
    (pin "1")
    (pin "2")
    (instances
      (project "scalenode-cm4-baseboard"
        (path ""
          (reference "R2") (unit 1)
        )
      )
    )
  )

  (symbol (lib_id "scalenode-cm4-baseboard:R_10k_0603") (at 140.97 55.88 270) (unit 1)
    (in_bom yes) (on_board yes) (dnp no)
    (property "Reference" "R4" (at 142.24 58.42 90)
      (effects (font (size 1.27 1.27) (thickness 0.15)) (justify left bottom))
    )
    (property "Value" "R_10k_0603" (at 128.27 76.2 0)
      (effects (font (size 1.27 1.27) (thickness 0.15)) (justify left bottom) hide)
    )
    (property "Footprint" "scalenode-cm4-baseboard-footprints:R_0603_1608Metric" (at 125.73 76.2 0)
      (effects (font (size 1.27 1.27) (thickness 0.15)) (justify left bottom) hide)
    )
    (property "Datasheet" "https://www.bourns.com/docs/product-datasheets/cr.pdf" (at 123.19 76.2 0)
      (effects (font (size 1.27 1.27) (thickness 0.15)) (justify left bottom) hide)
    )
    (property "Manufacturer" "Bourns" (at 118.11 76.2 0)
      (effects (font (size 1.27 1.27) (thickness 0.15)) (justify left bottom) hide)
    )
    (property "MPN" "CR0603-FX-1002ELF" (at 120.65 76.2 0)
      (effects (font (size 1.27 1.27) (thickness 0.15)) (justify left bottom) hide)
    )
    (property "Val" "10k" (at 142.24 58.42 90)
      (effects (font (size 1.27 1.27) (thickness 0.15)) (justify left top))
    )
    (property "License" "Apache-2.0" (at 115.57 76.2 0)
      (effects (font (size 1.27 1.27) (thickness 0.15)) (justify left bottom) hide)
    )
    (property "Author" "Antmicro" (at 113.03 76.2 0)
      (effects (font (size 1.27 1.27) (thickness 0.15)) (justify left bottom) hide)
    )
    (property "Tolerance" "1%" (at 130.81 76.2 0)
      (effects (font (size 1.27 1.27)) (justify left bottom) hide)
    )
    (pin "1")
    (pin "2")
    (instances
      (project "scalenode-cm4-baseboard"
        (path ""
          (reference "R4") (unit 1)
        )
      )
    )
  )

  (symbol (lib_id "scalenode-cm4-baseboard:R_10k_0603") (at 133.35 55.88 270) (unit 1)
    (in_bom yes) (on_board yes) (dnp no)
    (property "Reference" "R3" (at 134.62 58.42 90)
      (effects (font (size 1.27 1.27) (thickness 0.15)) (justify left bottom))
    )
    (property "Value" "R_10k_0603" (at 120.65 76.2 0)
      (effects (font (size 1.27 1.27) (thickness 0.15)) (justify left bottom) hide)
    )
    (property "Footprint" "scalenode-cm4-baseboard-footprints:R_0603_1608Metric" (at 118.11 76.2 0)
      (effects (font (size 1.27 1.27) (thickness 0.15)) (justify left bottom) hide)
    )
    (property "Datasheet" "https://www.bourns.com/docs/product-datasheets/cr.pdf" (at 115.57 76.2 0)
      (effects (font (size 1.27 1.27) (thickness 0.15)) (justify left bottom) hide)
    )
    (property "Manufacturer" "Bourns" (at 110.49 76.2 0)
      (effects (font (size 1.27 1.27) (thickness 0.15)) (justify left bottom) hide)
    )
    (property "MPN" "CR0603-FX-1002ELF" (at 113.03 76.2 0)
      (effects (font (size 1.27 1.27) (thickness 0.15)) (justify left bottom) hide)
    )
    (property "Val" "10k" (at 134.62 58.42 90)
      (effects (font (size 1.27 1.27) (thickness 0.15)) (justify left top))
    )
    (property "License" "Apache-2.0" (at 107.95 76.2 0)
      (effects (font (size 1.27 1.27) (thickness 0.15)) (justify left bottom) hide)
    )
    (property "Author" "Antmicro" (at 105.41 76.2 0)
      (effects (font (size 1.27 1.27) (thickness 0.15)) (justify left bottom) hide)
    )
    (property "Tolerance" "1%" (at 123.19 76.2 0)
      (effects (font (size 1.27 1.27)) (justify left bottom) hide)
    )
    (pin "1")
    (pin "2")
    (instances
      (project "scalenode-cm4-baseboard"
        (path ""
          (reference "R3") (unit 1)
        )
      )
    )
  )

  (symbol (lib_id "scalenode-cm4-baseboard:R_10k_0603") (at 125.73 55.88 270) (unit 1)
    (in_bom yes) (on_board yes) (dnp no)
    (property "Reference" "R1" (at 127 58.42 90)
      (effects (font (size 1.27 1.27) (thickness 0.15)) (justify left bottom))
    )
    (property "Value" "R_10k_0603" (at 113.03 76.2 0)
      (effects (font (size 1.27 1.27) (thickness 0.15)) (justify left bottom) hide)
    )
    (property "Footprint" "scalenode-cm4-baseboard-footprints:R_0603_1608Metric" (at 110.49 76.2 0)
      (effects (font (size 1.27 1.27) (thickness 0.15)) (justify left bottom) hide)
    )
    (property "Datasheet" "https://www.bourns.com/docs/product-datasheets/cr.pdf" (at 107.95 76.2 0)
      (effects (font (size 1.27 1.27) (thickness 0.15)) (justify left bottom) hide)
    )
    (property "Manufacturer" "Bourns" (at 102.87 76.2 0)
      (effects (font (size 1.27 1.27) (thickness 0.15)) (justify left bottom) hide)
    )
    (property "MPN" "CR0603-FX-1002ELF" (at 105.41 76.2 0)
      (effects (font (size 1.27 1.27) (thickness 0.15)) (justify left bottom) hide)
    )
    (property "Val" "10k" (at 127 58.42 90)
      (effects (font (size 1.27 1.27) (thickness 0.15)) (justify left top))
    )
    (property "License" "Apache-2.0" (at 100.33 76.2 0)
      (effects (font (size 1.27 1.27) (thickness 0.15)) (justify left bottom) hide)
    )
    (property "Author" "Antmicro" (at 97.79 76.2 0)
      (effects (font (size 1.27 1.27) (thickness 0.15)) (justify left bottom) hide)
    )
    (property "Tolerance" "1%" (at 115.57 76.2 0)
      (effects (font (size 1.27 1.27)) (justify left bottom) hide)
    )
    (pin "1")
    (pin "2")
    (instances
      (project "scalenode-cm4-baseboard"
        (path ""
          (reference "R1") (unit 1)
        )
      )
    )
  )
)
